# T6G (Grand Teton) — schematic netlist excerpt (pin names and nets, part order shuffled) for the footprints in the layout excerpt that follows; sources: Cadence DE-HDL packaged netlist, KiCad conversion of 04192023_DAF0TMB3IC0_F0TG_MB_C_brd_V02_OCP.brd

PC2343  Q_CAP  22UF 16V 20% X6S  pkg C0805  page 190 : A = SW_P3V3_AUX_FLT ; B = GND

PU207  MP5016GQHLZ  MP5016GQH-L-Z IC  pkg QFN8_2X1-5  page 141
  VCC  = P3V3_AUX
  GND  = GND
  ILIMIT  = P3V3_OCP_ILIMIT_2
  MODE  = P3V3_OCP_MODE_2
  SOURCE  = P3V3_OCP_V3_2_R
  GATE  = P3V3_OCP_GATE_PU207_2
  EN  = P3V3_OCP_EN_2
  DV_DT  = P3V3_OCP_DVDT_2

R3706  Q_RES  10K 1% EMPTY  pkg 0402LF  page 252 : A = P3V3_AUX ; B = PCA9548_PCIE0_ADDR1

(kicad_pcb
	(version 20260206)
	(generator "pcbnew")
	(generator_version "10.0")
	(general
		(thickness 1.6)
		(legacy_teardrops no)
	)
	(paper "A4")
	(title_block
		(title "04192023_DAF0TMB3IC0_F0TG_MB_C_brd_V02_OCP.brd")
		(comment 1 "Grand Teton / footprints 2480-2482 of 8354")
	)
	(layers
		(0 "F.Cu" signal "TOP")
		(4 "In1.Cu" signal "GND")
		(6 "In2.Cu" signal "IN1")
		(8 "In3.Cu" signal "GND1")
		(10 "In4.Cu" signal "IN2")
		(12 "In5.Cu" signal "GND2")
		(14 "In6.Cu" signal "IN3")
		(16 "In7.Cu" signal "GND3")
		(18 "In8.Cu" signal "VCC")
		(20 "In9.Cu" signal "VCC1")
		(22 "In10.Cu" signal "GND4")
		(24 "In11.Cu" signal "IN4")
		(26 "In12.Cu" signal "GND5")
		(28 "In13.Cu" signal "IN5")
		(30 "In14.Cu" signal "GND6")
		(32 "In15.Cu" signal "IN6")
		(34 "In16.Cu" signal "GND7")
		(2 "B.Cu" signal "BOTTOM")
		(9 "F.Adhes" user "F.Adhesive")
		(11 "B.Adhes" user "B.Adhesive")
		(13 "F.Paste" user "Package Geometry/Pastemask Top")
		(15 "B.Paste" user "Package Geometry/Pastemask Bottom")
		(5 "F.SilkS" user "Ref Des/Silkscreen Top")
		(7 "B.SilkS" user "Ref Des/Silkscreen Bottom")
		(1 "F.Mask" user "Board Geometry/Soldermask Top")
		(3 "B.Mask" user "Board Geometry/Soldermask Bottom")
		(17 "Dwgs.User" user "User.Drawings")
		(19 "Cmts.User" user "User.Comments")
		(21 "Eco1.User" user "User.Eco1")
		(23 "Eco2.User" user "User.Eco2")
		(25 "Edge.Cuts" user "Board Geometry/Outline")
		(27 "Margin" user)
		(31 "F.CrtYd" user "Package Geometry/Place Bound Top")
		(29 "B.CrtYd" user "Package Geometry/Place Bound Bottom")
		(35 "F.Fab" user "Ref Des/Assembly Top")
		(33 "B.Fab" user "Ref Des/Assembly Bottom")
	)
	(footprint ""
		(layer "F.Cu")
		(at 93.113352 -72.61098 -90)
		(property "Reference" "PU207"
			(at -3.701542 2.497328 0)
			(unlocked yes)
			(layer "F.SilkS")
			(effects
				(font
					(size 0.7874 0.5842)
					(thickness 0.1524)
				)
			)
		)
		(property "Value" ""
			(at 0 0 270)
			(layer "F.Fab")
			(effects
				(font
					(size 1.27 1.27)
				)
			)
		)
		(duplicate_pad_numbers_are_jumpers no)
		(fp_line
			(start -1.239774 1.495298)
			(end -1.239774 -1.495298)
			(stroke
				(width 0.1524)
				(type default)
			)
			(layer "F.SilkS")
		)
		(fp_line
			(start 1.239774 1.495298)
			(end -1.239774 1.495298)
			(stroke
				(width 0.1524)
				(type default)
			)
			(layer "F.SilkS")
		)
		(fp_line
			(start -1.239774 -1.495298)
			(end 1.239774 -1.495298)
			(stroke
				(width 0.1524)
				(type default)
			)
			(layer "F.SilkS")
		)
		(fp_line
			(start 1.239774 -1.495298)
			(end 1.239774 1.495298)
			(stroke
				(width 0.1524)
				(type default)
			)
			(layer "F.SilkS")
		)
		(fp_poly
			(pts
				(xy -1.843532 -0.966724) (xy -2.921 -1.32588) (xy -2.202688 -2.044446)
			)
			(stroke
				(width 0)
				(type default)
			)
			(fill yes)
			(layer "F.SilkS")
		)
		(fp_line
			(start -0.8001 1.050036)
			(end -0.8001 -1.050036)
			(stroke
				(width 0.1)
				(type default)
			)
			(layer "F.Fab")
		)
		(fp_line
			(start 0.8001 1.050036)
			(end -0.8001 1.050036)
			(stroke
				(width 0.1)
				(type default)
			)
			(layer "F.Fab")
		)
		(fp_line
			(start -0.8001 -1.050036)
			(end 0.8001 -1.050036)
			(stroke
				(width 0.1)
				(type default)
			)
			(layer "F.Fab")
		)
		(fp_line
			(start 0.8001 -1.050036)
			(end 0.8001 1.050036)
			(stroke
				(width 0.1)
				(type default)
			)
			(layer "F.Fab")
		)
		(fp_poly
			(pts
				(xy -2.458974 -0.508) (xy -2.458974 0.508) (xy -1.442974 0)
			)
			(stroke
				(width 0)
				(type default)
			)
			(fill yes)
			(layer "F.Fab")
		)
		(pad "1_2" smd circle
			(at -0.374904 0)
			(size 0 0)
			(layers "F.Cu" "F.Mask" "F.Paste")
			(net "P3V3_AUX")
		)
		(pad "3" smd rect
			(at -0.499872 0.999998 270)
			(size 0.254 0.7112)
			(layers "F.Cu" "F.Mask" "F.Paste")
			(net "GND")
		)
		(pad "4" smd rect
			(at 0 0.999998 270)
			(size 0.254 0.7112)
			(layers "F.Cu" "F.Mask" "F.Paste")
			(net "P3V3_OCP_ILIMIT_2")
		)
		(pad "5" smd rect
			(at 0.499872 0.999998 270)
			(size 0.254 0.7112)
			(layers "F.Cu" "F.Mask" "F.Paste")
			(net "P3V3_OCP_MODE_2")
		)
		(pad "6_7" smd circle
			(at 0.374904 0 180)
			(size 0 0)
			(layers "F.Cu" "F.Mask" "F.Paste")
			(net "P3V3_OCP_V3_2_R")
		)
		(pad "8" smd rect
			(at 0.499872 -0.999998 270)
			(size 0.254 0.7112)
			(layers "F.Cu" "F.Mask" "F.Paste")
			(net "P3V3_OCP_GATE_PU207_2")
		)
		(pad "9" smd rect
			(at 0 -0.999998 270)
			(size 0.254 0.7112)
			(layers "F.Cu" "F.Mask" "F.Paste")
			(net "P3V3_OCP_EN_2")
		)
		(pad "10" smd rect
			(at -0.499872 -0.999998 270)
			(size 0.254 0.7112)
			(layers "F.Cu" "F.Mask" "F.Paste")
			(net "P3V3_OCP_DVDT_2")
		)
	)
	(footprint ""
		(layer "F.Cu")
		(at 254.592836 -125.52045)
		(property "Reference" "R3706"
			(at 0 0 0)
			(layer "F.SilkS")
			(hide yes)
			(effects
				(font
					(size 1.27 1.27)
				)
			)
		)
		(property "Value" ""
			(at 0 0 0)
			(layer "F.Fab")
			(effects
				(font
					(size 1.27 1.27)
				)
			)
		)
		(duplicate_pad_numbers_are_jumpers no)
		(fp_line
			(start -0.7874 -0.4064)
			(end 0.7874 -0.4064)
			(stroke
				(width 0.1524)
				(type default)
			)
			(layer "F.SilkS")
		)
		(fp_line
			(start -0.7874 0.4064)
			(end -0.7874 -0.4064)
			(stroke
				(width 0.1524)
				(type default)
			)
			(layer "F.SilkS")
		)
		(fp_line
			(start 0.7874 -0.4064)
			(end 0.7874 0.4064)
			(stroke
				(width 0.1524)
				(type default)
			)
			(layer "F.SilkS")
		)
		(fp_line
			(start 0.7874 0.4064)
			(end -0.7874 0.4064)
			(stroke
				(width 0.1524)
				(type default)
			)
			(layer "F.SilkS")
		)
		(fp_line
			(start -0.67945 -0.305054)
			(end -0.12065 -0.305054)
			(stroke
				(width 0.1)
				(type default)
			)
			(layer "F.Fab")
		)
		(fp_line
			(start -0.67945 0.3048)
			(end -0.67945 -0.305054)
			(stroke
				(width 0.1)
				(type default)
			)
			(layer "F.Fab")
		)
		(fp_line
			(start -0.12065 -0.305054)
			(end -0.12065 -0.2794)
			(stroke
				(width 0.1)
				(type default)
			)
			(layer "F.Fab")
		)
		(fp_line
			(start -0.12065 -0.2794)
			(end 0.12065 -0.2794)
			(stroke
				(width 0.1)
				(type default)
			)
			(layer "F.Fab")
		)
		(fp_line
			(start -0.12065 0.2794)
			(end -0.12065 0.3048)
			(stroke
				(width 0.1)
				(type default)
			)
			(layer "F.Fab")
		)
		(fp_line
			(start -0.12065 0.3048)
			(end -0.67945 0.3048)
			(stroke
				(width 0.1)
				(type default)
			)
			(layer "F.Fab")
		)
		(fp_line
			(start 0.120396 0.2794)
			(end -0.12065 0.2794)
			(stroke
				(width 0.1)
				(type default)
			)
			(layer "F.Fab")
		)
		(fp_line
			(start 0.120396 0.3048)
			(end 0.120396 0.2794)
			(stroke
				(width 0.1)
				(type default)
			)
			(layer "F.Fab")
		)
		(fp_line
			(start 0.12065 -0.3048)
			(end 0.67945 -0.3048)
			(stroke
				(width 0.1)
				(type default)
			)
			(layer "F.Fab")
		)
		(fp_line
			(start 0.12065 -0.2794)
			(end 0.12065 -0.3048)
			(stroke
				(width 0.1)
				(type default)
			)
			(layer "F.Fab")
		)
		(fp_line
			(start 0.67945 -0.3048)
			(end 0.67945 0.3048)
			(stroke
				(width 0.1)
				(type default)
			)
			(layer "F.Fab")
		)
		(fp_line
			(start 0.67945 0.3048)
			(end 0.120396 0.3048)
			(stroke
				(width 0.1)
				(type default)
			)
			(layer "F.Fab")
		)
		(pad "1" smd circle
			(at -0.40005 0)
			(size 0 0)
			(layers "F.Cu" "F.Mask" "F.Paste")
			(net "P3V3_AUX")
		)
		(pad "2" smd circle
			(at 0.40005 0)
			(size 0 0)
			(layers "F.Cu" "F.Mask" "F.Paste")
			(net "PCA9548_PCIE0_ADDR1")
		)
	)
	(footprint ""
		(layer "F.Cu")
		(at 450.049392 -47.506382 -90)
		(property "Reference" "PC2343"
			(at 0 0 270)
			(layer "F.SilkS")
			(hide yes)
			(effects
				(font
					(size 1.27 1.27)
				)
			)
		)
		(property "Value" ""
			(at 0 0 270)
			(layer "F.Fab")
			(effects
				(font
					(size 1.27 1.27)
				)
			)
		)
		(duplicate_pad_numbers_are_jumpers no)
		(fp_line
			(start -1.524 0.762)
			(end -1.524 -0.762)
			(stroke
				(width 0.1524)
				(type default)
			)
			(layer "F.SilkS")
		)
		(fp_line
			(start 1.524 0.762)
			(end -1.524 0.762)
			(stroke
				(width 0.1524)
				(type default)
			)
			(layer "F.SilkS")
		)
		(fp_line
			(start -1.524 -0.762)
			(end 1.524 -0.762)
			(stroke
				(width 0.1524)
				(type default)
			)
			(layer "F.SilkS")
		)
		(fp_line
			(start 1.524 -0.762)
			(end 1.524 0.762)
			(stroke
				(width 0.1524)
				(type default)
			)
			(layer "F.SilkS")
		)
		(fp_line
			(start -1.1049 0.724916)
			(end 1.1049 0.724916)
			(stroke
				(width 0.1)
				(type default)
			)
			(layer "F.Fab")
		)
		(fp_line
			(start 1.1049 0.724916)
			(end 1.1049 -0.724916)
			(stroke
				(width 0.1)
				(type default)
			)
			(layer "F.Fab")
		)
		(fp_line
			(start -1.1049 -0.724916)
			(end -1.1049 0.724916)
			(stroke
				(width 0.1)
				(type default)
			)
			(layer "F.Fab")
		)
		(fp_line
			(start 1.1049 -0.724916)
			(end -1.1049 -0.724916)
			(stroke
				(width 0.1)
				(type default)
			)
			(layer "F.Fab")
		)
		(pad "1" smd rect
			(at -0.889 0 90)
			(size 1.016 1.27)
			(layers "F.Cu" "F.Mask" "F.Paste")
			(net "SW_P3V3_AUX_FLT")
		)
		(pad "2" smd rect
			(at 0.889 0 90)
			(size 1.016 1.27)
			(layers "F.Cu" "F.Mask" "F.Paste")
			(net "GND")
		)
	)
)
